# OCXO_DaughterCard_SiT5501.xlsx — OCXO_DaughterCard_SiT5501 (bom)
| Comment | Description | Designator | Footprint | LibRef | Quantity |
| Yageo_RC0402FR-07100RL | RES SMD 100 OHM 1% 1/16W 0402 | R5 | RESC1005X040N | RES-CMP-00538-3 | 1 |
| Yageo_RC0201JR-070RL | RES, 0.0 OHM, 0.5A, 1/20W, 0201 | R33 | RESC0603X026N | CMP-RES-00843-1 | 1 |
| Yageo_RC0201FR-0710KL | RES, 10K OHM, 1%, 1/20W, 200PPM/C, 0201 | R34 | RESC0603X026N | CMP-RES-00602-1 | 1 |
| Yageo_CC0402KRX7R7BB103 | CAP, CER, X7R, 0.01UF, 10%, 16V, 0402, 0.55MM T | C12, C14 | CAPC1005X055N | CAP-CMP-00257-3 | 2 |
| Wurth_9774040243R | STANDOFF, ROUND, M2X0.4 STEEL 4MM, 9774040243R | J1, J2 | TH000V_300DIAx400_001mt_9774040243R | CON-CMP-00164-1 | 2 |
| TI_DS90LV028AQMA/NOPB | IC, RVCR, DS90LV028AQ-Q1, DUAL, DIFF, LVDS, 400MBPS, SOIC-8 | U4 | SOP127P600X175_8N | INT-CMP-00017-4 | 1 |
| TI_DS90LV027AQMA/NOPB | IC, DRIVER, DS90LV027AQ, DUAL, DIFF, LVDS, 600MBPS, SOIC-8 | U3 | SOP127P600X175_8N | INT-CMP-00018-2 | 1 |
| TDK_MPZ1608S601ATA00 | FERRITE BEAD, 600 OHM @100MHZ, 25%, 1A, 0.150 OHM DCR, 0603, 0.95MM T | FL1, FL2 | INDC1608X095N | FER-CMP-00057-5 | 2 |
| Stackpole Electronics, Inc._RMCF1210ZT0R00 | RES, 0.0 OHM, 3A, 1/2W, 1210 | R1 | RESC3225X070N | RES-CMP-00829-3 | 1 |
| Stackpole Electronics, Inc._HCJ0402ZT0R00 | RES, 0.0 OHM, 1/8W, 6.5A, 0402 | R6, R7, R8 | RESC1005X045N | RES-CMP-00382-3 | 3 |
| SiTime_SiT5501AC-WU-33E0-10T | OSC, MEMS, STRATUM 3E, 10.000MHZ, 10PPB STAB, LVCMOS, 3.3V, O/P EN, 7.0X5.0X2.2MM, CQFN-10 | Y5 | SITIME_SPL-086-CQFN-010-C07050_REV_DRAFT | CMP-OSC-00029-2 | 1 |
| Samtec_HTSW-102-07-T-S | CONN, PIN, HEADER, 2POS, 2.54MM PITCH, 8.38MM H, VERT, TIN, TH | P9 | TH002_254_508x254x838_000mt_HTSW | CON-CMP-00061-3 | 1 |
| Samsung Electro-Mechanics_CL05B104JO5NNNC | CAP, CER, X7R, 0.1UF, 5%, 16V, 0402, 0.55MM T | C1, C6, C7, C9, C11, C13, C17, C19, C21, C23 | CAPC1005X055N | CAP-CMP-00271-3, CMP-CAP-00082-2 | 10 |
| Panasonic_ERJ-2RKF1003X | RES, 100K OHM, 1%, 1/10W, 100PPM/C, 0402 | R4 | RESC1005X040N | RES-CMP-00289-3 | 1 |
| NXP_PCT2075TP,147 | SENSOR DIGITAL -55C-125C 8HWSON | U5 | SON50P300X200X80-HS-9N_EP160x160_IPC | SNS-CMP-00004-1 | 1 |
| Murata_GRM188R61A106ME69D | CAP, CER, X5R, 10UF, 20%, 10V, 0603, 0.80MM T | C22 | CAPC1608X090N | CMP-CAP-00380-1 | 1 |
| Murata_GRM188D71A106MA73D | CAP, CER, X7T, 10UF, 20%, 10V, 0603, 1.00MM T | C8, C10, C18, C20 | CAPC1608X100N | CAP-CMP-00449-3 | 4 |
| Murata_GRM21BR61A226ME51L | CAP, CER, X5R, 22UF, 20%, 10V, 0805, 1.40MM T | C2, C3, C4 | CAPC2013X140N | CAP-CMP-00519-3 | 3 |
| Molex_539160208 | CONN, B2B/FPC, HEADER, 20-POS, 0.5MM PITCH, 4.0MM H, VERT, GOLD, SMT | P10 | SM020V_50_730x310x337_000mt_53916 | CON-CMP-00163-2 | 1 |
| Mill-Max_8600-0-05-80-00-00-03-0 | CONN, PC PIN, PRESS-FIT, 10.16MM LENGTH, TIN, TH | P1, P2, P3, P4, P5, P6, P7, P8, P11, P12 | TH001V_109DIA_000mt_8600-0 | CON-CMP-00162-1 | 10 |
| Microchip_AT24MAC602-XHM-B | IC, EEPROM, AT24MAC602, 2K-BIT (256 X 8), 1MHZ, I2C, 1.7V - 5.5V, TSSOP-8 | U2 | TSSOP65P640X120-8N | MEM-CMP-00010-1 | 1 |
| LMS1587IS-3.3/NOPB | 3A Low Dropout Fast Response Regulators, 3-pin TO-263, Pb-Free | U1 | KTT0003B_L | CMP-0062-00189-5 | 1 |
| Kemet_T491B476K010AT | CAP TANT 47UF 10% 10V 1411 | C5, C15, C16 | CAPMP3528X210N_T520 | CAP-CMP-00042-1 | 3 |
| 4871 | Round Standoff Threaded #2-56 Steel 0.063" (1.60mm) 1/16" | P13, P14, P15, P16 | Keystone_4871 | Keystone_4871 | 4 |
| 4.7K_1%_0402 | Chip Resistor, 4.7 KOhm, +/- 1%, 0.1 W, -55 to 155 degC, 0402 (1005 Metric), RoHS, Tape and Reel | R27, R28, R35, R36 | RESC1005X40X25LL05T05 | CMP-2002-01154-4 | 4 |
| 0_5%_0603 | Chip Resistor, 0 Ohm, +/- 5%, 0.1 W, -55 to 155 degC, 0603 (1608 Metric), RoHS, Tape and Reel | R16, R23 | RESC1608X55X25ML10T15 | CMP-2100-03667-1 | 2 |
| 0_1%_0402 |  | R11, R12, R17, R18, R19, R24, R25, R26, R30, R32 | RESC1005X40X25NL05T10 | CMP-1011-00001-2 | 10 |
